(kicad_pcb
	(version 20260206)
	(generator "pcbnew")
	(generator_version "10.0")
	(general
		(thickness 1.6)
		(legacy_teardrops no)
	)
	(paper "A4")
	(title_block
		(title "01162023_DA0F0TEBIF0_F0T_Expander_BD_F_brd_V02_OCP.brd")
		(comment 1 "Grand Teton / footprints 3119-3126 of 9728")
	)
	(layers
		(0 "F.Cu" signal "TOP")
		(4 "In1.Cu" signal "GND")
		(6 "In2.Cu" signal "VCC")
		(8 "In3.Cu" signal "VCC1")
		(10 "In4.Cu" signal "GND1")
		(12 "In5.Cu" signal "IN1")
		(14 "In6.Cu" signal "GND2")
		(16 "In7.Cu" signal "IN2")
		(18 "In8.Cu" signal "GND3")
		(20 "In9.Cu" signal "IN3")
		(22 "In10.Cu" signal "GND4")
		(24 "In11.Cu" signal "IN4")
		(26 "In12.Cu" signal "GND5")
		(28 "In13.Cu" signal "IN5")
		(30 "In14.Cu" signal "GND6")
		(32 "In15.Cu" signal "IN6")
		(34 "In16.Cu" signal "GND7")
		(2 "B.Cu" signal "BOTTOM")
		(9 "F.Adhes" user "F.Adhesive")
		(11 "B.Adhes" user "B.Adhesive")
		(13 "F.Paste" user "Package Geometry/Pastemask Top")
		(15 "B.Paste" user "Package Geometry/Pastemask Bottom")
		(5 "F.SilkS" user "Ref Des/Silkscreen Top")
		(7 "B.SilkS" user "Ref Des/Silkscreen Bottom")
		(1 "F.Mask" user "Board Geometry/Soldermask Top")
		(3 "B.Mask" user "Board Geometry/Soldermask Bottom")
		(17 "Dwgs.User" user "User.Drawings")
		(19 "Cmts.User" user "User.Comments")
		(21 "Eco1.User" user "User.Eco1")
		(23 "Eco2.User" user "User.Eco2")
		(25 "Edge.Cuts" user "Board Geometry/Outline")
		(27 "Margin" user)
		(31 "F.CrtYd" user "Package Geometry/Place Bound Top")
		(29 "B.CrtYd" user "Package Geometry/Place Bound Bottom")
		(35 "F.Fab" user "Ref Des/Assembly Top")
		(33 "B.Fab" user "Ref Des/Assembly Bottom")
	)
	(footprint ""
		(layer "F.Cu")
		(at 48.202088 -356.244906 90)
		(property "Reference" "C164"
			(at 0 0 90)
			(layer "F.SilkS")
			(hide yes)
			(effects
				(font
					(size 1.27 1.27)
				)
			)
		)
		(property "Value" ""
			(at 0 0 90)
			(layer "F.Fab")
			(effects
				(font
					(size 1.27 1.27)
				)
			)
		)
		(duplicate_pad_numbers_are_jumpers no)
		(fp_line
			(start 0.299974 -0.150114)
			(end 0.299974 0.150114)
			(stroke
				(width 0.1)
				(type default)
			)
			(layer "F.Fab")
		)
		(fp_line
			(start -0.299974 -0.150114)
			(end 0.299974 -0.150114)
			(stroke
				(width 0.1)
				(type default)
			)
			(layer "F.Fab")
		)
		(fp_line
			(start 0.299974 0.150114)
			(end -0.299974 0.150114)
			(stroke
				(width 0.1)
				(type default)
			)
			(layer "F.Fab")
		)
		(fp_line
			(start -0.299974 0.150114)
			(end -0.299974 -0.150114)
			(stroke
				(width 0.1)
				(type default)
			)
			(layer "F.Fab")
		)
		(pad "1" smd rect
			(at -0.2667 0 90)
			(size 0.3048 0.381)
			(layers "F.Cu" "F.Mask" "F.Paste")
			(net "P5E_PEX0_STN7_TX_DN<126>")
		)
		(pad "2" smd rect
			(at 0.2667 0 90)
			(size 0.3048 0.381)
			(layers "F.Cu" "F.Mask" "F.Paste")
			(net "P5E_PEX0_STN7_TX_C_DN<126>")
		)
	)
	(footprint ""
		(layer "F.Cu")
		(at 330.872846 -22.867366 90)
		(property "Reference" "C3949"
			(at 0 0 90)
			(layer "F.SilkS")
			(hide yes)
			(effects
				(font
					(size 1.27 1.27)
				)
			)
		)
		(property "Value" ""
			(at 0 0 90)
			(layer "F.Fab")
			(effects
				(font
					(size 1.27 1.27)
				)
			)
		)
		(duplicate_pad_numbers_are_jumpers no)
		(fp_line
			(start 0.7874 -0.4064)
			(end 0.7874 0.4064)
			(stroke
				(width 0.1524)
				(type default)
			)
			(layer "F.SilkS")
		)
		(fp_line
			(start -0.7874 -0.4064)
			(end 0.7874 -0.4064)
			(stroke
				(width 0.1524)
				(type default)
			)
			(layer "F.SilkS")
		)
		(fp_line
			(start 0.7874 0.4064)
			(end -0.7874 0.4064)
			(stroke
				(width 0.1524)
				(type default)
			)
			(layer "F.SilkS")
		)
		(fp_line
			(start -0.7874 0.4064)
			(end -0.7874 -0.4064)
			(stroke
				(width 0.1524)
				(type default)
			)
			(layer "F.SilkS")
		)
		(fp_line
			(start -0.12065 -0.305054)
			(end -0.12065 -0.2794)
			(stroke
				(width 0.1)
				(type default)
			)
			(layer "F.Fab")
		)
		(fp_line
			(start -0.67945 -0.305054)
			(end -0.12065 -0.305054)
			(stroke
				(width 0.1)
				(type default)
			)
			(layer "F.Fab")
		)
		(fp_line
			(start 0.67945 -0.3048)
			(end 0.67945 0.3048)
			(stroke
				(width 0.1)
				(type default)
			)
			(layer "F.Fab")
		)
		(fp_line
			(start 0.12065 -0.3048)
			(end 0.67945 -0.3048)
			(stroke
				(width 0.1)
				(type default)
			)
			(layer "F.Fab")
		)
		(fp_line
			(start 0.12065 -0.2794)
			(end 0.12065 -0.3048)
			(stroke
				(width 0.1)
				(type default)
			)
			(layer "F.Fab")
		)
		(fp_line
			(start -0.12065 -0.2794)
			(end 0.12065 -0.2794)
			(stroke
				(width 0.1)
				(type default)
			)
			(layer "F.Fab")
		)
		(fp_line
			(start 0.120396 0.2794)
			(end -0.12065 0.2794)
			(stroke
				(width 0.1)
				(type default)
			)
			(layer "F.Fab")
		)
		(fp_line
			(start -0.12065 0.2794)
			(end -0.12065 0.3048)
			(stroke
				(width 0.1)
				(type default)
			)
			(layer "F.Fab")
		)
		(fp_line
			(start 0.67945 0.3048)
			(end 0.120396 0.3048)
			(stroke
				(width 0.1)
				(type default)
			)
			(layer "F.Fab")
		)
		(fp_line
			(start 0.120396 0.3048)
			(end 0.120396 0.2794)
			(stroke
				(width 0.1)
				(type default)
			)
			(layer "F.Fab")
		)
		(fp_line
			(start -0.12065 0.3048)
			(end -0.67945 0.3048)
			(stroke
				(width 0.1)
				(type default)
			)
			(layer "F.Fab")
		)
		(fp_line
			(start -0.67945 0.3048)
			(end -0.67945 -0.305054)
			(stroke
				(width 0.1)
				(type default)
			)
			(layer "F.Fab")
		)
		(pad "1" smd circle
			(at -0.40005 0 90)
			(size 0 0)
			(layers "F.Cu" "F.Mask" "F.Paste")
			(net "P12V_SSD11")
		)
		(pad "2" smd circle
			(at 0.40005 0 90)
			(size 0 0)
			(layers "F.Cu" "F.Mask" "F.Paste")
			(net "GND")
		)
	)
	(footprint ""
		(layer "F.Cu")
		(at 140.074142 -175.897286 180)
		(property "Reference" "R1100"
			(at 0 0 180)
			(layer "F.SilkS")
			(hide yes)
			(effects
				(font
					(size 1.27 1.27)
				)
			)
		)
		(property "Value" ""
			(at 0 0 180)
			(layer "F.Fab")
			(effects
				(font
					(size 1.27 1.27)
				)
			)
		)
		(duplicate_pad_numbers_are_jumpers no)
		(fp_line
			(start -0.7874 -0.4064)
			(end 0.7874 -0.4064)
			(stroke
				(width 0.1524)
				(type default)
			)
			(layer "F.SilkS")
		)
		(fp_line
			(start 0.67945 0.3048)
			(end 0.120396 0.3048)
			(stroke
				(width 0.1)
				(type default)
			)
			(layer "F.Fab")
		)
		(fp_line
			(start 0.67945 -0.3048)
			(end 0.67945 0.3048)
			(stroke
				(width 0.1)
				(type default)
			)
			(layer "F.Fab")
		)
		(fp_line
			(start 0.12065 -0.2794)
			(end 0.12065 -0.3048)
			(stroke
				(width 0.1)
				(type default)
			)
			(layer "F.Fab")
		)
		(fp_line
			(start 0.12065 -0.3048)
			(end 0.67945 -0.3048)
			(stroke
				(width 0.1)
				(type default)
			)
			(layer "F.Fab")
		)
		(fp_line
			(start 0.120396 0.3048)
			(end 0.120396 0.2794)
			(stroke
				(width 0.1)
				(type default)
			)
			(layer "F.Fab")
		)
		(fp_line
			(start 0.120396 0.2794)
			(end -0.12065 0.2794)
			(stroke
				(width 0.1)
				(type default)
			)
			(layer "F.Fab")
		)
		(fp_line
			(start -0.12065 0.3048)
			(end -0.67945 0.3048)
			(stroke
				(width 0.1)
				(type default)
			)
			(layer "F.Fab")
		)
		(fp_line
			(start -0.12065 0.2794)
			(end -0.12065 0.3048)
			(stroke
				(width 0.1)
				(type default)
			)
			(layer "F.Fab")
		)
		(fp_line
			(start -0.12065 -0.2794)
			(end 0.12065 -0.2794)
			(stroke
				(width 0.1)
				(type default)
			)
			(layer "F.Fab")
		)
		(fp_line
			(start -0.12065 -0.305054)
			(end -0.12065 -0.2794)
			(stroke
				(width 0.1)
				(type default)
			)
			(layer "F.Fab")
		)
		(fp_line
			(start -0.67945 0.3048)
			(end -0.67945 -0.305054)
			(stroke
				(width 0.1)
				(type default)
			)
			(layer "F.Fab")
		)
		(fp_line
			(start -0.67945 -0.305054)
			(end -0.12065 -0.305054)
			(stroke
				(width 0.1)
				(type default)
			)
			(layer "F.Fab")
		)
		(pad "1" smd circle
			(at -0.40005 0 180)
			(size 0 0)
			(layers "F.Cu" "F.Mask" "F.Paste")
			(net "CLK_100M_DB2000QL_NIC3_R_DP")
		)
		(pad "2" smd circle
			(at 0.40005 0 180)
			(size 0 0)
			(layers "F.Cu" "F.Mask" "F.Paste")
			(net "CLK_100M_DB2000QL_NIC3_DP")
		)
	)
	(footprint ""
		(layer "F.Cu")
		(at 238.235998 -48.77689 180)
		(property "Reference" "PC548"
			(at 0 0 180)
			(layer "F.SilkS")
			(hide yes)
			(effects
				(font
					(size 1.27 1.27)
				)
			)
		)
		(property "Value" ""
			(at 0 0 180)
			(layer "F.Fab")
			(effects
				(font
					(size 1.27 1.27)
				)
			)
		)
		(duplicate_pad_numbers_are_jumpers no)
		(fp_line
			(start 0.7874 0.4064)
			(end -0.7874 0.4064)
			(stroke
				(width 0.1524)
				(type default)
			)
			(layer "F.SilkS")
		)
		(fp_line
			(start 0.7874 -0.4064)
			(end 0.7874 0.4064)
			(stroke
				(width 0.1524)
				(type default)
			)
			(layer "F.SilkS")
		)
		(fp_line
			(start -0.7874 0.4064)
			(end -0.7874 -0.4064)
			(stroke
				(width 0.1524)
				(type default)
			)
			(layer "F.SilkS")
		)
		(fp_line
			(start -0.7874 -0.4064)
			(end 0.7874 -0.4064)
			(stroke
				(width 0.1524)
				(type default)
			)
			(layer "F.SilkS")
		)
		(fp_line
			(start 0.67945 0.3048)
			(end 0.120396 0.3048)
			(stroke
				(width 0.1)
				(type default)
			)
			(layer "F.Fab")
		)
		(fp_line
			(start 0.67945 -0.3048)
			(end 0.67945 0.3048)
			(stroke
				(width 0.1)
				(type default)
			)
			(layer "F.Fab")
		)
		(fp_line
			(start 0.12065 -0.2794)
			(end 0.12065 -0.3048)
			(stroke
				(width 0.1)
				(type default)
			)
			(layer "F.Fab")
		)
		(fp_line
			(start 0.12065 -0.3048)
			(end 0.67945 -0.3048)
			(stroke
				(width 0.1)
				(type default)
			)
			(layer "F.Fab")
		)
		(fp_line
			(start 0.120396 0.3048)
			(end 0.120396 0.2794)
			(stroke
				(width 0.1)
				(type default)
			)
			(layer "F.Fab")
		)
		(fp_line
			(start 0.120396 0.2794)
			(end -0.12065 0.2794)
			(stroke
				(width 0.1)
				(type default)
			)
			(layer "F.Fab")
		)
		(fp_line
			(start -0.12065 0.3048)
			(end -0.67945 0.3048)
			(stroke
				(width 0.1)
				(type default)
			)
			(layer "F.Fab")
		)
		(fp_line
			(start -0.12065 0.2794)
			(end -0.12065 0.3048)
			(stroke
				(width 0.1)
				(type default)
			)
			(layer "F.Fab")
		)
		(fp_line
			(start -0.12065 -0.2794)
			(end 0.12065 -0.2794)
			(stroke
				(width 0.1)
				(type default)
			)
			(layer "F.Fab")
		)
		(fp_line
			(start -0.12065 -0.305054)
			(end -0.12065 -0.2794)
			(stroke
				(width 0.1)
				(type default)
			)
			(layer "F.Fab")
		)
		(fp_line
			(start -0.67945 0.3048)
			(end -0.67945 -0.305054)
			(stroke
				(width 0.1)
				(type default)
			)
			(layer "F.Fab")
		)
		(fp_line
			(start -0.67945 -0.305054)
			(end -0.12065 -0.305054)
			(stroke
				(width 0.1)
				(type default)
			)
			(layer "F.Fab")
		)
		(pad "1" smd circle
			(at -0.40005 0 180)
			(size 0 0)
			(layers "F.Cu" "F.Mask" "F.Paste")
			(net "P3V3_SSD8")
		)
		(pad "2" smd circle
			(at 0.40005 0 180)
			(size 0 0)
			(layers "F.Cu" "F.Mask" "F.Paste")
			(net "GND")
		)
	)
	(footprint ""
		(layer "F.Cu")
		(at 312.21934 -133.480302 180)
		(property "Reference" "C442"
			(at 0 0 180)
			(layer "F.SilkS")
			(hide yes)
			(effects
				(font
					(size 1.27 1.27)
				)
			)
		)
		(property "Value" ""
			(at 0 0 180)
			(layer "F.Fab")
			(effects
				(font
					(size 1.27 1.27)
				)
			)
		)
		(duplicate_pad_numbers_are_jumpers no)
		(fp_line
			(start 0.299974 0.150114)
			(end -0.299974 0.150114)
			(stroke
				(width 0.1)
				(type default)
			)
			(layer "F.Fab")
		)
		(fp_line
			(start 0.299974 -0.150114)
			(end 0.299974 0.150114)
			(stroke
				(width 0.1)
				(type default)
			)
			(layer "F.Fab")
		)
		(fp_line
			(start -0.299974 0.150114)
			(end -0.299974 -0.150114)
			(stroke
				(width 0.1)
				(type default)
			)
			(layer "F.Fab")
		)
		(fp_line
			(start -0.299974 -0.150114)
			(end 0.299974 -0.150114)
			(stroke
				(width 0.1)
				(type default)
			)
			(layer "F.Fab")
		)
		(pad "1" smd rect
			(at -0.2667 0 180)
			(size 0.3048 0.381)
			(layers "F.Cu" "F.Mask" "F.Paste")
			(net "P5E_PEX2_STN0_TX_DN<6>")
		)
		(pad "2" smd rect
			(at 0.2667 0 180)
			(size 0.3048 0.381)
			(layers "F.Cu" "F.Mask" "F.Paste")
			(net "P5E_PEX2_STN0_TX_C_DN<6>")
		)
	)
	(footprint ""
		(layer "F.Cu")
		(at 382.154176 -307.415438 45)
		(property "Reference" "R1421"
			(at 0 0 45)
			(layer "F.SilkS")
			(hide yes)
			(effects
				(font
					(size 1.27 1.27)
				)
			)
		)
		(property "Value" ""
			(at 0 0 45)
			(layer "F.Fab")
			(effects
				(font
					(size 1.27 1.27)
				)
			)
		)
		(duplicate_pad_numbers_are_jumpers no)
		(fp_line
			(start -0.787389 -0.406267)
			(end 0.787389 -0.406267)
			(stroke
				(width 0.1524)
				(type default)
			)
			(layer "F.SilkS")
		)
		(fp_line
			(start -0.787389 0.406267)
			(end -0.787389 -0.406267)
			(stroke
				(width 0.1524)
				(type default)
			)
			(layer "F.SilkS")
		)
		(fp_line
			(start 0.787389 -0.406267)
			(end 0.787389 0.406267)
			(stroke
				(width 0.1524)
				(type default)
			)
			(layer "F.SilkS")
		)
		(fp_line
			(start 0.787389 0.406267)
			(end -0.787389 0.406267)
			(stroke
				(width 0.1524)
				(type default)
			)
			(layer "F.SilkS")
		)
		(fp_line
			(start -0.679446 -0.305149)
			(end -0.120695 -0.304969)
			(stroke
				(width 0.1)
				(type default)
			)
			(layer "F.Fab")
		)
		(fp_line
			(start -0.120695 -0.304969)
			(end -0.120695 -0.279466)
			(stroke
				(width 0.1)
				(type default)
			)
			(layer "F.Fab")
		)
		(fp_line
			(start -0.120695 -0.279466)
			(end 0.120695 -0.279466)
			(stroke
				(width 0.1)
				(type default)
			)
			(layer "F.Fab")
		)
		(fp_line
			(start -0.679446 0.30479)
			(end -0.679446 -0.305149)
			(stroke
				(width 0.1)
				(type default)
			)
			(layer "F.Fab")
		)
		(fp_line
			(start 0.120515 -0.30479)
			(end 0.679446 -0.30479)
			(stroke
				(width 0.1)
				(type default)
			)
			(layer "F.Fab")
		)
		(fp_line
			(start 0.120695 -0.279466)
			(end 0.120515 -0.30479)
			(stroke
				(width 0.1)
				(type default)
			)
			(layer "F.Fab")
		)
		(fp_line
			(start -0.120695 0.279466)
			(end -0.120515 0.30479)
			(stroke
				(width 0.1)
				(type default)
			)
			(layer "F.Fab")
		)
		(fp_line
			(start -0.120515 0.30479)
			(end -0.679446 0.30479)
			(stroke
				(width 0.1)
				(type default)
			)
			(layer "F.Fab")
		)
		(fp_line
			(start 0.679446 -0.30479)
			(end 0.679446 0.30479)
			(stroke
				(width 0.1)
				(type default)
			)
			(layer "F.Fab")
		)
		(fp_line
			(start 0.120335 0.279466)
			(end -0.120695 0.279466)
			(stroke
				(width 0.1)
				(type default)
			)
			(layer "F.Fab")
		)
		(fp_line
			(start 0.120515 0.30479)
			(end 0.120335 0.279466)
			(stroke
				(width 0.1)
				(type default)
			)
			(layer "F.Fab")
		)
		(fp_line
			(start 0.679446 0.30479)
			(end 0.120515 0.30479)
			(stroke
				(width 0.1)
				(type default)
			)
			(layer "F.Fab")
		)
		(pad "1" smd circle
			(at -0.40005 0 45)
			(size 0 0)
			(layers "F.Cu" "F.Mask" "F.Paste")
			(net "GND")
		)
		(pad "2" smd circle
			(at 0.40005 0 45)
			(size 0 0)
			(layers "F.Cu" "F.Mask" "F.Paste")
			(net "PEX3_DBG_MODE1")
		)
	)
	(footprint ""
		(layer "F.Cu")
		(at 335.915 -234.061 -90)
		(property "Reference" "R6283"
			(at 0 0 270)
			(layer "F.SilkS")
			(hide yes)
			(effects
				(font
					(size 1.27 1.27)
				)
			)
		)
		(property "Value" ""
			(at 0 0 270)
			(layer "F.Fab")
			(effects
				(font
					(size 1.27 1.27)
				)
			)
		)
		(duplicate_pad_numbers_are_jumpers no)
		(fp_line
			(start -0.7874 0.4064)
			(end -0.7874 -0.4064)
			(stroke
				(width 0.1524)
				(type default)
			)
			(layer "F.SilkS")
		)
		(fp_line
			(start 0.7874 0.4064)
			(end -0.7874 0.4064)
			(stroke
				(width 0.1524)
				(type default)
			)
			(layer "F.SilkS")
		)
		(fp_line
			(start -0.7874 -0.4064)
			(end 0.7874 -0.4064)
			(stroke
				(width 0.1524)
				(type default)
			)
			(layer "F.SilkS")
		)
		(fp_line
			(start 0.7874 -0.4064)
			(end 0.7874 0.4064)
			(stroke
				(width 0.1524)
				(type default)
			)
			(layer "F.SilkS")
		)
		(fp_line
			(start -0.67945 0.3048)
			(end -0.67945 -0.305054)
			(stroke
				(width 0.1)
				(type default)
			)
			(layer "F.Fab")
		)
		(fp_line
			(start -0.12065 0.3048)
			(end -0.67945 0.3048)
			(stroke
				(width 0.1)
				(type default)
			)
			(layer "F.Fab")
		)
		(fp_line
			(start 0.120396 0.3048)
			(end 0.120396 0.2794)
			(stroke
				(width 0.1)
				(type default)
			)
			(layer "F.Fab")
		)
		(fp_line
			(start 0.67945 0.3048)
			(end 0.120396 0.3048)
			(stroke
				(width 0.1)
				(type default)
			)
			(layer "F.Fab")
		)
		(fp_line
			(start -0.12065 0.2794)
			(end -0.12065 0.3048)
			(stroke
				(width 0.1)
				(type default)
			)
			(layer "F.Fab")
		)
		(fp_line
			(start 0.120396 0.2794)
			(end -0.12065 0.2794)
			(stroke
				(width 0.1)
				(type default)
			)
			(layer "F.Fab")
		)
		(fp_line
			(start -0.12065 -0.2794)
			(end 0.12065 -0.2794)
			(stroke
				(width 0.1)
				(type default)
			)
			(layer "F.Fab")
		)
		(fp_line
			(start 0.12065 -0.2794)
			(end 0.12065 -0.3048)
			(stroke
				(width 0.1)
				(type default)
			)
			(layer "F.Fab")
		)
		(fp_line
			(start 0.12065 -0.3048)
			(end 0.67945 -0.3048)
			(stroke
				(width 0.1)
				(type default)
			)
			(layer "F.Fab")
		)
		(fp_line
			(start 0.67945 -0.3048)
			(end 0.67945 0.3048)
			(stroke
				(width 0.1)
				(type default)
			)
			(layer "F.Fab")
		)
		(fp_line
			(start -0.67945 -0.305054)
			(end -0.12065 -0.305054)
			(stroke
				(width 0.1)
				(type default)
			)
			(layer "F.Fab")
		)
		(fp_line
			(start -0.12065 -0.305054)
			(end -0.12065 -0.2794)
			(stroke
				(width 0.1)
				(type default)
			)
			(layer "F.Fab")
		)
		(pad "1" smd circle
			(at -0.40005 0 270)
			(size 0 0)
			(layers "F.Cu" "F.Mask" "F.Paste")
			(net "P3V3_AUX")
		)
		(pad "2" smd circle
			(at 0.40005 0 270)
			(size 0 0)
			(layers "F.Cu" "F.Mask" "F.Paste")
			(net "SYS_PWR_READY_R_N")
		)
	)
	(footprint ""
		(layer "F.Cu")
		(at 166.184072 -350.098614 90)
		(property "Reference" "C399"
			(at 0 0 90)
			(layer "F.SilkS")
			(hide yes)
			(effects
				(font
					(size 1.27 1.27)
				)
			)
		)
		(property "Value" ""
			(at 0 0 90)
			(layer "F.Fab")
			(effects
				(font
					(size 1.27 1.27)
				)
			)
		)
		(duplicate_pad_numbers_are_jumpers no)
		(fp_line
			(start 0.299974 -0.150114)
			(end 0.299974 0.150114)
			(stroke
				(width 0.1)
				(type default)
			)
			(layer "F.Fab")
		)
		(fp_line
			(start -0.299974 -0.150114)
			(end 0.299974 -0.150114)
			(stroke
				(width 0.1)
				(type default)
			)
			(layer "F.Fab")
		)
		(fp_line
			(start 0.299974 0.150114)
			(end -0.299974 0.150114)
			(stroke
				(width 0.1)
				(type default)
			)
			(layer "F.Fab")
		)
		(fp_line
			(start -0.299974 0.150114)
			(end -0.299974 -0.150114)
			(stroke
				(width 0.1)
				(type default)
			)
			(layer "F.Fab")
		)
		(pad "1" smd rect
			(at -0.2667 0 90)
			(size 0.3048 0.381)
			(layers "F.Cu" "F.Mask" "F.Paste")
			(net "P5E_PEX1_STN7_TX_DN<114>")
		)
		(pad "2" smd rect
			(at 0.2667 0 90)
			(size 0.3048 0.381)
			(layers "F.Cu" "F.Mask" "F.Paste")
			(net "P5E_PEX1_STN7_TX_C_DN<114>")
		)
	)
)
